# S9S_MB_2U (Grand Teton) — schematic netlist excerpt (pin names and nets, part order shuffled) for the footprints in the layout excerpt that follows; sources: Cadence DE-HDL packaged netlist, KiCad conversion of 03242023_DA0F0TMBIJ0_F0T_Motherboard_J_brd_V01_OCP.brd

PC279  Q_CAP  100NF 50V 10% X7R  pkg C0402  page 268 : A = SW_PVCCIN_CPU0_BOOT3_R ; B = SW_PVCCIN_CPU0_BOOTR3
R4591  Q_RES  10K 1% EMPTY  pkg 0402LF  page 195 : A = P3V3_AUX ; B = FM_BOARD_BMC_SKU_ID3
H32  HOLE  EMPTY  pkg TH  page 311 : \1\ = GND

(kicad_pcb
	(version 20260206)
	(generator "pcbnew")
	(generator_version "10.0")
	(general
		(thickness 1.6)
		(legacy_teardrops no)
	)
	(paper "A4")
	(title_block
		(title "03242023_DA0F0TMBIJ0_F0T_Motherboard_J_brd_V01_OCP.brd")
		(comment 1 "Grand Teton / footprints 3047-3049 of 6105")
	)
	(layers
		(0 "F.Cu" signal "TOP")
		(4 "In1.Cu" signal "GND")
		(6 "In2.Cu" signal "IN1")
		(8 "In3.Cu" signal "GND1")
		(10 "In4.Cu" signal "IN2")
		(12 "In5.Cu" signal "GND2")
		(14 "In6.Cu" signal "IN3")
		(16 "In7.Cu" signal "GND3")
		(18 "In8.Cu" signal "VCC")
		(20 "In9.Cu" signal "VCC1")
		(22 "In10.Cu" signal "GND4")
		(24 "In11.Cu" signal "IN4")
		(26 "In12.Cu" signal "GND5")
		(28 "In13.Cu" signal "IN5")
		(30 "In14.Cu" signal "GND6")
		(32 "In15.Cu" signal "IN6")
		(34 "In16.Cu" signal "GND7")
		(2 "B.Cu" signal "BOTTOM")
		(9 "F.Adhes" user "F.Adhesive")
		(11 "B.Adhes" user "B.Adhesive")
		(13 "F.Paste" user "Package Geometry/Pastemask Top")
		(15 "B.Paste" user "Package Geometry/Pastemask Bottom")
		(5 "F.SilkS" user "Ref Des/Silkscreen Top")
		(7 "B.SilkS" user "Ref Des/Silkscreen Bottom")
		(1 "F.Mask" user "Board Geometry/Soldermask Top")
		(3 "B.Mask" user "Board Geometry/Soldermask Bottom")
		(17 "Dwgs.User" user "User.Drawings")
		(19 "Cmts.User" user "User.Comments")
		(21 "Eco1.User" user "User.Eco1")
		(23 "Eco2.User" user "User.Eco2")
		(25 "Edge.Cuts" user "Board Geometry/Outline")
		(27 "Margin" user)
		(31 "F.CrtYd" user "Package Geometry/Place Bound Top")
		(29 "B.CrtYd" user "Package Geometry/Place Bound Bottom")
		(35 "F.Fab" user "Ref Des/Assembly Top")
		(33 "B.Fab" user "Ref Des/Assembly Bottom")
	)
	(footprint ""
		(layer "F.Cu")
		(at 362.991908 -338.17814 -90)
		(property "Reference" "PC279"
			(at 0 0 270)
			(layer "F.SilkS")
			(hide yes)
			(effects
				(font
					(size 1.27 1.27)
				)
			)
		)
		(property "Value" ""
			(at 0 0 270)
			(layer "F.Fab")
			(effects
				(font
					(size 1.27 1.27)
				)
			)
		)
		(duplicate_pad_numbers_are_jumpers no)
		(fp_line
			(start -0.7874 0.4064)
			(end -0.7874 -0.4064)
			(stroke
				(width 0.1524)
				(type default)
			)
			(layer "F.SilkS")
		)
		(fp_line
			(start 0.7874 0.4064)
			(end -0.7874 0.4064)
			(stroke
				(width 0.1524)
				(type default)
			)
			(layer "F.SilkS")
		)
		(fp_line
			(start -0.7874 -0.4064)
			(end 0.7874 -0.4064)
			(stroke
				(width 0.1524)
				(type default)
			)
			(layer "F.SilkS")
		)
		(fp_line
			(start 0.7874 -0.4064)
			(end 0.7874 0.4064)
			(stroke
				(width 0.1524)
				(type default)
			)
			(layer "F.SilkS")
		)
		(fp_line
			(start -0.67945 0.3048)
			(end -0.67945 -0.305054)
			(stroke
				(width 0.1)
				(type default)
			)
			(layer "F.Fab")
		)
		(fp_line
			(start -0.12065 0.3048)
			(end -0.67945 0.3048)
			(stroke
				(width 0.1)
				(type default)
			)
			(layer "F.Fab")
		)
		(fp_line
			(start 0.120396 0.3048)
			(end 0.120396 0.2794)
			(stroke
				(width 0.1)
				(type default)
			)
			(layer "F.Fab")
		)
		(fp_line
			(start 0.67945 0.3048)
			(end 0.120396 0.3048)
			(stroke
				(width 0.1)
				(type default)
			)
			(layer "F.Fab")
		)
		(fp_line
			(start -0.12065 0.2794)
			(end -0.12065 0.3048)
			(stroke
				(width 0.1)
				(type default)
			)
			(layer "F.Fab")
		)
		(fp_line
			(start 0.120396 0.2794)
			(end -0.12065 0.2794)
			(stroke
				(width 0.1)
				(type default)
			)
			(layer "F.Fab")
		)
		(fp_line
			(start -0.12065 -0.2794)
			(end 0.12065 -0.2794)
			(stroke
				(width 0.1)
				(type default)
			)
			(layer "F.Fab")
		)
		(fp_line
			(start 0.12065 -0.2794)
			(end 0.12065 -0.3048)
			(stroke
				(width 0.1)
				(type default)
			)
			(layer "F.Fab")
		)
		(fp_line
			(start 0.12065 -0.3048)
			(end 0.67945 -0.3048)
			(stroke
				(width 0.1)
				(type default)
			)
			(layer "F.Fab")
		)
		(fp_line
			(start 0.67945 -0.3048)
			(end 0.67945 0.3048)
			(stroke
				(width 0.1)
				(type default)
			)
			(layer "F.Fab")
		)
		(fp_line
			(start -0.67945 -0.305054)
			(end -0.12065 -0.305054)
			(stroke
				(width 0.1)
				(type default)
			)
			(layer "F.Fab")
		)
		(fp_line
			(start -0.12065 -0.305054)
			(end -0.12065 -0.2794)
			(stroke
				(width 0.1)
				(type default)
			)
			(layer "F.Fab")
		)
		(pad "1" smd circle
			(at -0.40005 0 270)
			(size 0 0)
			(layers "F.Cu" "F.Mask" "F.Paste")
			(net "SW_PVCCIN_CPU0_BOOT3_R")
		)
		(pad "2" smd circle
			(at 0.40005 0 270)
			(size 0 0)
			(layers "F.Cu" "F.Mask" "F.Paste")
			(net "SW_PVCCIN_CPU0_BOOTR3")
		)
	)
	(footprint ""
		(layer "F.Cu")
		(at 179.2224 -93.538548 90)
		(property "Reference" "R4591"
			(at 0 0 90)
			(layer "F.SilkS")
			(hide yes)
			(effects
				(font
					(size 1.27 1.27)
				)
			)
		)
		(property "Value" ""
			(at 0 0 90)
			(layer "F.Fab")
			(effects
				(font
					(size 1.27 1.27)
				)
			)
		)
		(duplicate_pad_numbers_are_jumpers no)
		(fp_line
			(start 0.7874 -0.4064)
			(end 0.7874 0.4064)
			(stroke
				(width 0.1524)
				(type default)
			)
			(layer "F.SilkS")
		)
		(fp_line
			(start -0.7874 -0.4064)
			(end 0.7874 -0.4064)
			(stroke
				(width 0.1524)
				(type default)
			)
			(layer "F.SilkS")
		)
		(fp_line
			(start 0.7874 0.4064)
			(end -0.7874 0.4064)
			(stroke
				(width 0.1524)
				(type default)
			)
			(layer "F.SilkS")
		)
		(fp_line
			(start -0.7874 0.4064)
			(end -0.7874 -0.4064)
			(stroke
				(width 0.1524)
				(type default)
			)
			(layer "F.SilkS")
		)
		(fp_line
			(start -0.12065 -0.305054)
			(end -0.12065 -0.2794)
			(stroke
				(width 0.1)
				(type default)
			)
			(layer "F.Fab")
		)
		(fp_line
			(start -0.67945 -0.305054)
			(end -0.12065 -0.305054)
			(stroke
				(width 0.1)
				(type default)
			)
			(layer "F.Fab")
		)
		(fp_line
			(start 0.67945 -0.3048)
			(end 0.67945 0.3048)
			(stroke
				(width 0.1)
				(type default)
			)
			(layer "F.Fab")
		)
		(fp_line
			(start 0.12065 -0.3048)
			(end 0.67945 -0.3048)
			(stroke
				(width 0.1)
				(type default)
			)
			(layer "F.Fab")
		)
		(fp_line
			(start 0.12065 -0.2794)
			(end 0.12065 -0.3048)
			(stroke
				(width 0.1)
				(type default)
			)
			(layer "F.Fab")
		)
		(fp_line
			(start -0.12065 -0.2794)
			(end 0.12065 -0.2794)
			(stroke
				(width 0.1)
				(type default)
			)
			(layer "F.Fab")
		)
		(fp_line
			(start 0.120396 0.2794)
			(end -0.12065 0.2794)
			(stroke
				(width 0.1)
				(type default)
			)
			(layer "F.Fab")
		)
		(fp_line
			(start -0.12065 0.2794)
			(end -0.12065 0.3048)
			(stroke
				(width 0.1)
				(type default)
			)
			(layer "F.Fab")
		)
		(fp_line
			(start 0.67945 0.3048)
			(end 0.120396 0.3048)
			(stroke
				(width 0.1)
				(type default)
			)
			(layer "F.Fab")
		)
		(fp_line
			(start 0.120396 0.3048)
			(end 0.120396 0.2794)
			(stroke
				(width 0.1)
				(type default)
			)
			(layer "F.Fab")
		)
		(fp_line
			(start -0.12065 0.3048)
			(end -0.67945 0.3048)
			(stroke
				(width 0.1)
				(type default)
			)
			(layer "F.Fab")
		)
		(fp_line
			(start -0.67945 0.3048)
			(end -0.67945 -0.305054)
			(stroke
				(width 0.1)
				(type default)
			)
			(layer "F.Fab")
		)
		(pad "1" smd rect
			(at -0.40005 0 270)
			(size 0.4572 0.508)
			(layers "F.Cu" "F.Mask" "F.Paste")
			(net "P3V3_AUX")
		)
		(pad "2" smd rect
			(at 0.40005 0 270)
			(size 0.4572 0.508)
			(layers "F.Cu" "F.Mask" "F.Paste")
			(net "FM_BOARD_BMC_SKU_ID3")
		)
	)
	(footprint ""
		(layer "F.Cu")
		(at 100.382832 -47.049944)
		(property "Reference" "H32"
			(at -1.7272 -4.511548 0)
			(unlocked yes)
			(layer "B.SilkS")
			(effects
				(font
					(size 0.7874 0.5842)
					(thickness 0.1524)
				)
				(justify left mirror)
			)
		)
		(property "Value" ""
			(at 0 0 0)
			(layer "F.Fab")
			(effects
				(font
					(size 1.27 1.27)
				)
			)
		)
		(duplicate_pad_numbers_are_jumpers no)
		(pad "1" thru_hole circle
			(at 0 0)
			(size 4.5212 4.5212)
			(drill 3.81)
			(layers "*.Cu" "*.Mask")
			(remove_unused_layers no)
			(net "GND")
			(clearance -0.1016)
			(padstack
				(mode front_inner_back)
				(layer "Inner"
					(shape circle)
					(size 5.6134 5.6134)
					(clearance -0.6477)
				)
				(layer "B.Cu"
					(shape circle)
					(size 8.001 8.001)
					(clearance -1.8415)
				)
			)
		)
	)
)
